(kicad_pcb
	(version 20241229)
	(generator "pcbnew")
	(generator_version "9.0")
	(general
		(thickness 1.711)
		(legacy_teardrops no)
	)
	(paper "A4")
	(title_block
		(title "Antmicro Baseboard for Jetson AGX Thor")
		(date "2026-02-18")
		(rev "1.1.0")
		(company "Antmicro Ltd")
		(comment 1 "www.antmicro.com")
		(comment 9 "footprints 209-211 of 1170")
	)
	(layers
		(0 "F.Cu" signal)
		(4 "In1.Cu" signal)
		(6 "In2.Cu" signal)
		(8 "In3.Cu" signal)
		(10 "In4.Cu" jumper)
		(12 "In5.Cu" signal)
		(14 "In6.Cu" signal)
		(16 "In7.Cu" signal)
		(18 "In8.Cu" signal)
		(2 "B.Cu" signal)
		(9 "F.Adhes" user "F.Adhesive")
		(11 "B.Adhes" user "B.Adhesive")
		(13 "F.Paste" user)
		(15 "B.Paste" user)
		(5 "F.SilkS" user "F.Silkscreen")
		(7 "B.SilkS" user "B.Silkscreen")
		(1 "F.Mask" user)
		(3 "B.Mask" user)
		(17 "Dwgs.User" user "User.Drawings")
		(19 "Cmts.User" user "User.Comments")
		(21 "Eco1.User" user "User.Eco1")
		(23 "Eco2.User" user "User.Eco2")
		(25 "Edge.Cuts" user)
		(27 "Margin" user)
		(31 "F.CrtYd" user "F.Courtyard")
		(29 "B.CrtYd" user "B.Courtyard")
		(35 "F.Fab" user)
		(33 "B.Fab" user)
	)
	(footprint "antmicro-footprints:USB-C_Receptacle_Kycon_KUSBX-SL2-CS1N24-B-TR"
		(locked yes)
		(layer "F.Cu")
		(at 236.455532 76.21 90)
		(descr "USB-C (USB TYPE-C) USB 3.2 Gen 2 (USB 3.1 Gen 2, Superspeed + (USB 3.1)) Receptacle Connector 24 Position Through Hole, Right Angle")
		(tags "CONNECTOR, USB")
		(property "Reference" "J7"
			(at 3.11 -10.785532 180)
			(layer "F.SilkS")
			(effects
				(font
					(size 0.7 0.7)
					(thickness 0.15)
				)
				(justify left bottom)
			)
		)
		(property "Value" "USB-C_Kycon_KUSBX-SL2-CS1N24-B-TR"
			(at 0 7.5 90)
			(layer "F.Fab")
			(effects
				(font
					(size 0.7 0.7)
					(thickness 0.15)
				)
				(justify right top)
			)
		)
		(property "Datasheet" "https://www.kycon.com/Pub_Eng_Draw/KUSBX-SL2-CS1N24-B-TR.pdf"
			(at 0 0 90)
			(layer "F.Fab")
			(hide yes)
			(effects
				(font
					(size 1.27 1.27)
					(thickness 0.15)
				)
			)
		)
		(property "Description" "USB-C (USB TYPE-C) USB 3.2 Gen 2 (USB 3.1 Gen 2, Superspeed + (USB 3.1)) USB PD Receptacle Connector 24 Position Surface Mount"
			(at 0 0 90)
			(layer "F.Fab")
			(hide yes)
			(effects
				(font
					(size 1.27 1.27)
					(thickness 0.15)
				)
			)
		)
		(property "MPN" "KUSBX-SL2-CS1N24-B-TR"
			(at 0 0 270)
			(unlocked yes)
			(layer "F.Fab")
			(hide yes)
			(effects
				(font
					(size 1 1)
					(thickness 0.15)
				)
			)
		)
		(property "Manufacturer" "Kycon"
			(at 0 0 270)
			(unlocked yes)
			(layer "F.Fab")
			(hide yes)
			(effects
				(font
					(size 1 1)
					(thickness 0.15)
				)
			)
		)
		(property "License" "Apache-2.0"
			(at 0 0 270)
			(unlocked yes)
			(layer "F.Fab")
			(hide yes)
			(effects
				(font
					(size 1 1)
					(thickness 0.15)
				)
			)
		)
		(property "Author" "Antmicro"
			(at 0 0 270)
			(unlocked yes)
			(layer "F.Fab")
			(hide yes)
			(effects
				(font
					(size 1 1)
					(thickness 0.15)
				)
			)
		)
		(sheetname "/USB Debug, PD/")
		(sheetfile "usb_debug_pd.kicad_sch")
		(attr smd)
		(fp_line
			(start 1 -8.8)
			(end 1 -8.8)
			(stroke
				(width 0.15)
				(type solid)
			)
			(layer "F.SilkS")
		)
		(fp_line
			(start 1 -8.8)
			(end -1 -8.8)
			(stroke
				(width 0.15)
				(type solid)
			)
			(layer "F.SilkS")
		)
		(fp_line
			(start -1 -8.8)
			(end 1 -8.8)
			(stroke
				(width 0.15)
				(type solid)
			)
			(layer "F.SilkS")
		)
		(fp_line
			(start -1 -8.8)
			(end -1 -8.8)
			(stroke
				(width 0.15)
				(type solid)
			)
			(layer "F.SilkS")
		)
		(fp_rect
			(start -4 -9.4)
			(end 4 5.65)
			(stroke
				(width 0.05)
				(type solid)
			)
			(fill no)
			(layer "F.CrtYd")
		)
		(fp_line
			(start 2.25 -8.8)
			(end -2.25 -8.8)
			(stroke
				(width 0.15)
				(type solid)
			)
			(layer "F.Fab")
		)
		(fp_line
			(start -2.25 -8.8)
			(end -2.25 5.5)
			(stroke
				(width 0.15)
				(type solid)
			)
			(layer "F.Fab")
		)
		(fp_line
			(start 2.25 5.5)
			(end 2.25 -8.8)
			(stroke
				(width 0.15)
				(type solid)
			)
			(layer "F.Fab")
		)
		(fp_line
			(start -2.25 5.5)
			(end 2.25 5.5)
			(stroke
				(width 0.15)
				(type solid)
			)
			(layer "F.Fab")
		)
		(fp_text user "License: Apache-2.0"
			(at -5.47 10.9 90)
			(layer "F.Fab")
			(effects
				(font
					(size 0.7 0.7)
					(thickness 0.15)
				)
				(justify left bottom)
			)
		)
		(fp_text user "${REFERENCE}"
			(at -5.47 8.5 90)
			(layer "F.Fab")
			(effects
				(font
					(size 0.7 0.7)
					(thickness 0.15)
				)
				(justify left bottom)
			)
		)
		(fp_text user "Author: Antmicro"
			(at -5.47 9.7 90)
			(layer "F.Fab")
			(effects
				(font
					(size 0.7 0.7)
					(thickness 0.15)
				)
				(justify left bottom)
			)
		)
		(pad "" np_thru_hole circle
			(at 0 -7.6 90)
			(size 1.1 1.1)
			(drill 1.1)
			(layers "*.Cu" "*.Mask")
		)
		(pad "" np_thru_hole circle
			(at 0 0 90)
			(size 1 1)
			(drill 1)
			(layers "*.Cu" "*.Mask")
		)
		(pad "A1" smd rect
			(at 1.1375 -6.525 180)
			(size 0.25 1.625)
			(layers "F.Cu" "F.Mask" "F.Paste")
			(net 1 "GND")
			(pinfunction "GND")
			(pintype "power_in")
		)
		(pad "A2" smd rect
			(at 1.1375 -6.025 180)
			(size 0.25 1.625)
			(layers "F.Cu" "F.Mask" "F.Paste")
			(net 1194 "unconnected-(J7-TX_{1}+-PadA2)")
			(pinfunction "TX_{1}+")
			(pintype "bidirectional+no_connect")
		)
		(pad "A3" smd rect
			(at 1.1375 -5.525 180)
			(size 0.25 1.625)
			(layers "F.Cu" "F.Mask" "F.Paste")
			(net 1193 "unconnected-(J7-TX_{1}--PadA3)")
			(pinfunction "TX_{1}-")
			(pintype "bidirectional+no_connect")
		)
		(pad "A4" smd rect
			(at 1.1375 -5.025 180)
			(size 0.25 1.625)
			(layers "F.Cu" "F.Mask" "F.Paste")
			(net 176 "/USB Debug, PD/USBC0_VBUS")
			(pinfunction "VBUS")
			(pintype "power_in")
		)
		(pad "A5" smd rect
			(at 1.1375 -4.525 180)
			(size 0.25 1.625)
			(layers "F.Cu" "F.Mask" "F.Paste")
			(net 514 "/USB Debug, PD/USBC0_CC1")
			(pinfunction "CC_{1}")
			(pintype "bidirectional")
		)
		(pad "A6" smd rect
			(at 1.1375 -4.025 180)
			(size 0.25 1.625)
			(layers "F.Cu" "F.Mask" "F.Paste")
			(net 489 "/USB Debug, PD/USBC0_D_P")
			(pinfunction "D_{A}+")
			(pintype "bidirectional")
		)
		(pad "A7" smd rect
			(at 1.1375 -3.525 180)
			(size 0.25 1.625)
			(layers "F.Cu" "F.Mask" "F.Paste")
			(net 488 "/USB Debug, PD/USBC0_D_N")
			(pinfunction "D_{A}-")
			(pintype "bidirectional")
		)
		(pad "A8" smd rect
			(at 1.1375 -3.025 180)
			(size 0.25 1.625)
			(layers "F.Cu" "F.Mask" "F.Paste")
			(net 813 "unconnected-(J7-SBU_{1}-PadA8)")
			(pinfunction "SBU_{1}")
			(pintype "bidirectional+no_connect")
		)
		(pad "A9" smd rect
			(at 1.1375 -2.525 180)
			(size 0.25 1.625)
			(layers "F.Cu" "F.Mask" "F.Paste")
			(net 176 "/USB Debug, PD/USBC0_VBUS")
			(pinfunction "VBUS")
			(pintype "passive")
		)
		(pad "A10" smd rect
			(at 1.1375 -2.025 180)
			(size 0.25 1.625)
			(layers "F.Cu" "F.Mask" "F.Paste")
			(net 1195 "unconnected-(J7-RX_{2}--PadA10)")
			(pinfunction "RX_{2}-")
			(pintype "bidirectional+no_connect")
		)
		(pad "A11" smd rect
			(at 1.1375 -1.525 180)
			(size 0.25 1.625)
			(layers "F.Cu" "F.Mask" "F.Paste")
			(net 1196 "unconnected-(J7-RX_{2}+-PadA11)")
			(pinfunction "RX_{2}+")
			(pintype "bidirectional+no_connect")
		)
		(pad "A12" smd rect
			(at 1.1375 -1.025 180)
			(size 0.25 1.625)
			(layers "F.Cu" "F.Mask" "F.Paste")
			(net 1 "GND")
			(pinfunction "GND")
			(pintype "passive")
		)
		(pad "B1" smd rect
			(at -1.1375 -1.025 180)
			(size 0.25 1.625)
			(layers "F.Cu" "F.Mask" "F.Paste")
			(net 1 "GND")
			(pinfunction "GND")
			(pintype "passive")
		)
		(pad "B2" smd rect
			(at -1.1375 -1.525 180)
			(size 0.25 1.625)
			(layers "F.Cu" "F.Mask" "F.Paste")
			(net 1192 "unconnected-(J7-TX_{2}+-PadB2)")
			(pinfunction "TX_{2}+")
			(pintype "bidirectional+no_connect")
		)
		(pad "B3" smd rect
			(at -1.1375 -2.025 180)
			(size 0.25 1.625)
			(layers "F.Cu" "F.Mask" "F.Paste")
			(net 1198 "unconnected-(J7-TX_{2}--PadB3)")
			(pinfunction "TX_{2}-")
			(pintype "bidirectional+no_connect")
		)
		(pad "B4" smd rect
			(at -1.1375 -2.525 180)
			(size 0.25 1.625)
			(layers "F.Cu" "F.Mask" "F.Paste")
			(net 176 "/USB Debug, PD/USBC0_VBUS")
			(pinfunction "VBUS")
			(pintype "passive")
		)
		(pad "B5" smd rect
			(at -1.1375 -3.025 180)
			(size 0.25 1.625)
			(layers "F.Cu" "F.Mask" "F.Paste")
			(net 515 "/USB Debug, PD/USBC0_CC2")
			(pinfunction "CC_{2}")
			(pintype "bidirectional")
		)
		(pad "B6" smd rect
			(at -1.1375 -3.525 180)
			(size 0.25 1.625)
			(layers "F.Cu" "F.Mask" "F.Paste")
			(net 489 "/USB Debug, PD/USBC0_D_P")
			(pinfunction "D_{B}+")
			(pintype "bidirectional")
		)
		(pad "B7" smd rect
			(at -1.1375 -4.025 180)
			(size 0.25 1.625)
			(layers "F.Cu" "F.Mask" "F.Paste")
			(net 488 "/USB Debug, PD/USBC0_D_N")
			(pinfunction "D_{B}-")
			(pintype "bidirectional")
		)
		(pad "B8" smd rect
			(at -1.1375 -4.525 180)
			(size 0.25 1.625)
			(layers "F.Cu" "F.Mask" "F.Paste")
			(net 814 "unconnected-(J7-SBU_{2}-PadB8)")
			(pinfunction "SBU_{2}")
			(pintype "bidirectional+no_connect")
		)
		(pad "B9" smd rect
			(at -1.1375 -5.025 180)
			(size 0.25 1.625)
			(layers "F.Cu" "F.Mask" "F.Paste")
			(net 176 "/USB Debug, PD/USBC0_VBUS")
			(pinfunction "VBUS")
			(pintype "passive")
		)
		(pad "B10" smd rect
			(at -1.1375 -5.525 180)
			(size 0.25 1.625)
			(layers "F.Cu" "F.Mask" "F.Paste")
			(net 1197 "unconnected-(J7-RX_{1}--PadB10)")
			(pinfunction "RX_{1}-")
			(pintype "bidirectional+no_connect")
		)
		(pad "B11" smd rect
			(at -1.1375 -6.025 180)
			(size 0.25 1.625)
			(layers "F.Cu" "F.Mask" "F.Paste")
			(net 1199 "unconnected-(J7-RX_{1}+-PadB11)")
			(pinfunction "RX_{1}+")
			(pintype "bidirectional+no_connect")
		)
		(pad "B12" smd rect
			(at -1.1375 -6.525 180)
			(size 0.25 1.625)
			(layers "F.Cu" "F.Mask" "F.Paste")
			(net 1 "GND")
			(pinfunction "GND")
			(pintype "passive")
		)
		(pad "SH" thru_hole oval
			(at -3 -7.849 90)
			(size 1 2.05)
			(drill oval 0.6 1.65)
			(layers "*.Cu" "*.Mask")
			(remove_unused_layers no)
			(net 1 "GND")
			(pinfunction "SH")
			(pintype "passive")
		)
		(pad "SH" thru_hole oval
			(at -3 0.25 90)
			(size 1 2.05)
			(drill oval 0.6 1.65)
			(layers "*.Cu" "*.Mask")
			(remove_unused_layers no)
			(net 1 "GND")
			(pinfunction "SH")
			(pintype "passive")
		)
		(pad "SH" thru_hole oval
			(at 3 -7.849 90)
			(size 1 2.05)
			(drill oval 0.6 1.65)
			(layers "*.Cu" "*.Mask")
			(remove_unused_layers no)
			(net 1 "GND")
			(pinfunction "SH")
			(pintype "passive")
		)
		(pad "SH" thru_hole oval
			(at 3 0.25 90)
			(size 1 2.05)
			(drill oval 0.6 1.65)
			(layers "*.Cu" "*.Mask")
			(remove_unused_layers no)
			(net 1 "GND")
			(pinfunction "SH")
			(pintype "passive")
		)
	)
	(footprint "antmicro-footprints:C_0402_1005Metric"
		(layer "F.Cu")
		(at 206.75 92.470856 180)
		(descr "Capacitor SMD 0402")
		(tags "capacitor SMD 0402")
		(property "Reference" "C321"
			(at 3.65 -0.929144 180)
			(layer "F.SilkS")
			(effects
				(font
					(size 0.7 0.7)
					(thickness 0.15)
				)
				(justify left bottom)
			)
		)
		(property "Value" "C_100n_0402"
			(at -1.022927 2.155213 180)
			(layer "F.Fab")
			(effects
				(font
					(size 0.7 0.7)
					(thickness 0.15)
				)
				(justify left bottom)
			)
		)
		(property "Datasheet" "https://www.murata.com/products/productdetail?partno=GRM155R61H104KE14%23"
			(at 0 0 180)
			(layer "F.Fab")
			(hide yes)
			(effects
				(font
					(size 1.27 1.27)
					(thickness 0.15)
				)
			)
		)
		(property "Description" "SMD Multilayer Ceramic Capacitor, 0.1 µF, 50 V, 0402 [1005 Metric], ± 10%, X5R, GRM Series"
			(at 0 0 180)
			(layer "F.Fab")
			(hide yes)
			(effects
				(font
					(size 1.27 1.27)
					(thickness 0.15)
				)
			)
		)
		(property "Manufacturer" "Murata"
			(at 0 0 180)
			(unlocked yes)
			(layer "F.Fab")
			(hide yes)
			(effects
				(font
					(size 1 1)
					(thickness 0.15)
				)
			)
		)
		(property "MPN" "GRM155R61H104KE14D"
			(at 0 0 180)
			(unlocked yes)
			(layer "F.Fab")
			(hide yes)
			(effects
				(font
					(size 1 1)
					(thickness 0.15)
				)
			)
		)
		(property "Val" "100n"
			(at 0 0 180)
			(unlocked yes)
			(layer "F.Fab")
			(hide yes)
			(effects
				(font
					(size 1 1)
					(thickness 0.15)
				)
			)
		)
		(property "License" "Apache-2.0"
			(at 0 0 180)
			(unlocked yes)
			(layer "F.Fab")
			(hide yes)
			(effects
				(font
					(size 1 1)
					(thickness 0.15)
				)
			)
		)
		(property "Author" "Antmicro"
			(at 0 0 180)
			(unlocked yes)
			(layer "F.Fab")
			(hide yes)
			(effects
				(font
					(size 1 1)
					(thickness 0.15)
				)
			)
		)
		(property "Voltage" "50V"
			(at 0 0 180)
			(unlocked yes)
			(layer "F.Fab")
			(hide yes)
			(effects
				(font
					(size 1 1)
					(thickness 0.15)
				)
			)
		)
		(property "Dielectric" "X5R"
			(at 0 0 180)
			(unlocked yes)
			(layer "F.Fab")
			(hide yes)
			(effects
				(font
					(size 1 1)
					(thickness 0.15)
				)
			)
		)
		(sheetname "/SoM_IO2/")
		(sheetfile "som_io2.kicad_sch")
		(attr smd)
		(fp_rect
			(start -0.925 -0.47)
			(end 0.925 0.47)
			(stroke
				(width 0.05)
				(type default)
			)
			(fill no)
			(layer "F.CrtYd")
		)
		(fp_line
			(start 0.504 0.248)
			(end -0.494 0.248)
			(stroke
				(width 0.15)
				(type solid)
			)
			(layer "F.Fab")
		)
		(fp_line
			(start 0.504 -0.25)
			(end 0.504 0.248)
			(stroke
				(width 0.15)
				(type solid)
			)
			(layer "F.Fab")
		)
		(fp_line
			(start -0.494 0.248)
			(end -0.494 -0.25)
			(stroke
				(width 0.15)
				(type solid)
			)
			(layer "F.Fab")
		)
		(fp_line
			(start -0.494 -0.25)
			(end 0.504 -0.25)
			(stroke
				(width 0.15)
				(type solid)
			)
			(layer "F.Fab")
		)
		(fp_text user "${REFERENCE}"
			(at -0.939 4.599 180)
			(layer "F.Fab")
			(effects
				(font
					(size 0.7 0.7)
					(thickness 0.15)
				)
				(justify left bottom)
			)
		)
		(fp_text user "License: Apache-2.0"
			(at -0.939 5.799 180)
			(layer "F.Fab")
			(effects
				(font
					(size 0.7 0.7)
					(thickness 0.15)
				)
				(justify left bottom)
			)
		)
		(fp_text user "Author: Antmicro"
			(at -0.939 3.399 180)
			(layer "F.Fab")
			(effects
				(font
					(size 0.7 0.7)
					(thickness 0.15)
				)
				(justify left bottom)
			)
		)
		(pad "1" smd roundrect
			(at -0.48 0 180)
			(size 0.59 0.64)
			(layers "F.Cu" "F.Mask" "F.Paste")
			(roundrect_rratio 0.25)
			(net 553 "/SoM_IO2/DP0.TX3-")
			(pintype "passive")
		)
		(pad "2" smd roundrect
			(at 0.48 0 180)
			(size 0.59 0.64)
			(layers "F.Cu" "F.Mask" "F.Paste")
			(roundrect_rratio 0.25)
			(net 799 "/SoM_IO2/DP0.TX3_C-")
			(pintype "passive")
		)
	)
	(footprint "antmicro-footprints:SC-70-6"
		(layer "F.Cu")
		(at 91 63.5)
		(property "Reference" "U74"
			(at -1.6 -1.2 0)
			(layer "F.SilkS")
			(effects
				(font
					(size 0.7 0.7)
					(thickness 0.15)
				)
				(justify left bottom)
			)
		)
		(property "Value" "SN74LVC2G07DCKR"
			(at 0 2.2 0)
			(layer "F.Fab")
			(effects
				(font
					(size 0.7 0.7)
					(thickness 0.15)
				)
				(justify left bottom)
			)
		)
		(property "Datasheet" "https://www.ti.com/lit/gpn/sn74lvc2g07"
			(at 0 0 0)
			(layer "F.Fab")
			(hide yes)
			(effects
				(font
					(size 1.27 1.27)
					(thickness 0.15)
				)
			)
		)
		(property "Description" "Buffer / Line Driver, SN74LVC2G07DCKR, 1.65 V to 5.5 V, SC-70-5"
			(at 0 0 0)
			(layer "F.Fab")
			(hide yes)
			(effects
				(font
					(size 1.27 1.27)
					(thickness 0.15)
				)
			)
		)
		(property "MPN" "SN74LVC2G07DCKR"
			(at 0 0 0)
			(unlocked yes)
			(layer "F.Fab")
			(hide yes)
			(effects
				(font
					(size 1 1)
					(thickness 0.15)
				)
			)
		)
		(property "Manufacturer" "Texas Instruments"
			(at 0 0 0)
			(unlocked yes)
			(layer "F.Fab")
			(hide yes)
			(effects
				(font
					(size 1 1)
					(thickness 0.15)
				)
			)
		)
		(property "Author" "Antmicro"
			(at 0 0 0)
			(unlocked yes)
			(layer "F.Fab")
			(hide yes)
			(effects
				(font
					(size 1 1)
					(thickness 0.15)
				)
			)
		)
		(property "License" "Apache-2.0"
			(at 0 0 0)
			(unlocked yes)
			(layer "F.Fab")
			(hide yes)
			(effects
				(font
					(size 1 1)
					(thickness 0.15)
				)
			)
		)
		(sheetname "/SoM_Power/")
		(sheetfile "som_power.kicad_sch")
		(attr smd)
		(fp_line
			(start -0.7 -1)
			(end 0.7 -1)
			(stroke
				(width 0.15)
				(type solid)
			)
			(layer "F.SilkS")
		)
		(fp_line
			(start -0.7 1)
			(end 0.7 1)
			(stroke
				(width 0.15)
				(type solid)
			)
			(layer "F.SilkS")
		)
		(fp_circle
			(center -1.1 -1)
			(end -1.025 -1)
			(stroke
				(width 0.15)
				(type solid)
			)
			(fill yes)
			(layer "F.SilkS")
		)
		(fp_rect
			(start -1.6 -1.1)
			(end 1.6 1.1)
			(stroke
				(width 0.05)
				(type solid)
			)
			(fill no)
			(layer "F.CrtYd")
		)
		(fp_line
			(start -0.593 0.993)
			(end -0.593 -0.706)
			(stroke
				(width 0.15)
				(type solid)
			)
			(layer "F.Fab")
		)
		(fp_line
			(start -0.293 -1.006)
			(end -0.593 -0.706)
			(stroke
				(width 0.15)
				(type solid)
			)
			(layer "F.Fab")
		)
		(fp_line
			(start -0.293 -1.006)
			(end 0.657 -1.006)
			(stroke
				(width 0.15)
				(type solid)
			)
			(layer "F.Fab")
		)
		(fp_line
			(start 0.657 -1.006)
			(end 0.657 0.993)
			(stroke
				(width 0.15)
				(type solid)
			)
			(layer "F.Fab")
		)
		(fp_line
			(start 0.657 0.993)
			(end -0.593 0.993)
			(stroke
				(width 0.15)
				(type solid)
			)
			(layer "F.Fab")
		)
		(fp_text user "Author: Antmicro"
			(at -1.45 4.2 0)
			(layer "F.Fab")
			(effects
				(font
					(size 0.7 0.7)
					(thickness 0.15)
				)
				(justify left bottom)
			)
		)
		(fp_text user "License: Apache-2.0"
			(at -1.45 6.6 0)
			(layer "F.Fab")
			(effects
				(font
					(size 0.7 0.7)
					(thickness 0.15)
				)
				(justify left bottom)
			)
		)
		(fp_text user "${REFERENCE}"
			(at -1.45 5.4 0)
			(layer "F.Fab")
			(effects
				(font
					(size 0.7 0.7)
					(thickness 0.15)
				)
				(justify left bottom)
			)
		)
		(pad "1" smd roundrect
			(at -1.1 -0.65)
			(size 0.85 0.35)
			(layers "F.Cu" "F.Mask" "F.Paste")
			(roundrect_rratio 0.25)
			(net 246 "/SoM_Power/~{VDDIN_PWR_BAD}")
			(pinfunction "1A")
			(pintype "input")
		)
		(pad "2" smd roundrect
			(at -1.1 0)
			(size 0.85 0.35)
			(layers "F.Cu" "F.Mask" "F.Paste")
			(roundrect_rratio 0.25)
			(net 1 "GND")
			(pinfunction "GND")
			(pintype "power_in")
		)
		(pad "3" smd roundrect
			(at -1.1 0.65)
			(size 0.85 0.35)
			(layers "F.Cu" "F.Mask" "F.Paste")
			(roundrect_rratio 0.25)
			(net 1032 "/SoM_Power/~{FORCE_SHDN}")
			(pinfunction "2A")
			(pintype "input")
		)
		(pad "4" smd roundrect
			(at 1.1 0.65)
			(size 0.85 0.35)
			(layers "F.Cu" "F.Mask" "F.Paste")
			(roundrect_rratio 0.25)
			(net 1304 "Net-(U74-2Y)")
			(pinfunction "2Y")
			(pintype "open_collector")
		)
		(pad "5" smd roundrect
			(at 1.1 0)
			(size 0.85 0.35)
			(layers "F.Cu" "F.Mask" "F.Paste")
			(roundrect_rratio 0.25)
			(net 4 "+3V3_AON")
			(pinfunction "V_{CC}")
			(pintype "power_in")
		)
		(pad "6" smd roundrect
			(at 1.1 -0.65)
			(size 0.85 0.35)
			(layers "F.Cu" "F.Mask" "F.Paste")
			(roundrect_rratio 0.25)
			(net 1287 "/SoM_Power/MODULE_POWER_ON")
			(pinfunction "1Y")
			(pintype "open_collector")
		)
	)
)
